(kicad_pcb
	(version 20260206)
	(generator "pcbnew")
	(generator_version "10.0")
	(general
		(thickness 1.6)
		(legacy_teardrops no)
	)
	(paper "A4")
	(title_block
		(title "04192023_DAF0TMB3IC0_F0TG_MB_C_brd_V02_OCP.brd")
		(comment 1 "Grand Teton / footprints 4286-4292 of 8354")
	)
	(layers
		(0 "F.Cu" signal "TOP")
		(4 "In1.Cu" signal "GND")
		(6 "In2.Cu" signal "IN1")
		(8 "In3.Cu" signal "GND1")
		(10 "In4.Cu" signal "IN2")
		(12 "In5.Cu" signal "GND2")
		(14 "In6.Cu" signal "IN3")
		(16 "In7.Cu" signal "GND3")
		(18 "In8.Cu" signal "VCC")
		(20 "In9.Cu" signal "VCC1")
		(22 "In10.Cu" signal "GND4")
		(24 "In11.Cu" signal "IN4")
		(26 "In12.Cu" signal "GND5")
		(28 "In13.Cu" signal "IN5")
		(30 "In14.Cu" signal "GND6")
		(32 "In15.Cu" signal "IN6")
		(34 "In16.Cu" signal "GND7")
		(2 "B.Cu" signal "BOTTOM")
		(9 "F.Adhes" user "F.Adhesive")
		(11 "B.Adhes" user "B.Adhesive")
		(13 "F.Paste" user "Package Geometry/Pastemask Top")
		(15 "B.Paste" user "Package Geometry/Pastemask Bottom")
		(5 "F.SilkS" user "Ref Des/Silkscreen Top")
		(7 "B.SilkS" user "Ref Des/Silkscreen Bottom")
		(1 "F.Mask" user "Board Geometry/Soldermask Top")
		(3 "B.Mask" user "Board Geometry/Soldermask Bottom")
		(17 "Dwgs.User" user "User.Drawings")
		(19 "Cmts.User" user "User.Comments")
		(21 "Eco1.User" user "User.Eco1")
		(23 "Eco2.User" user "User.Eco2")
		(25 "Edge.Cuts" user "Board Geometry/Outline")
		(27 "Margin" user)
		(31 "F.CrtYd" user "Package Geometry/Place Bound Top")
		(29 "B.CrtYd" user "Package Geometry/Place Bound Bottom")
		(35 "F.Fab" user "Ref Des/Assembly Top")
		(33 "B.Fab" user "Ref Des/Assembly Bottom")
	)
	(footprint ""
		(layer "F.Cu")
		(at 379.292104 -178.0921 90)
		(property "Reference" "PC560"
			(at 0 0 90)
			(layer "F.SilkS")
			(hide yes)
			(effects
				(font
					(size 1.27 1.27)
				)
			)
		)
		(property "Value" ""
			(at 0 0 90)
			(layer "F.Fab")
			(effects
				(font
					(size 1.27 1.27)
				)
			)
		)
		(duplicate_pad_numbers_are_jumpers no)
		(fp_line
			(start 0.7874 -0.4064)
			(end 0.7874 0.4064)
			(stroke
				(width 0.1524)
				(type default)
			)
			(layer "F.SilkS")
		)
		(fp_line
			(start -0.7874 -0.4064)
			(end 0.7874 -0.4064)
			(stroke
				(width 0.1524)
				(type default)
			)
			(layer "F.SilkS")
		)
		(fp_line
			(start 0.7874 0.4064)
			(end -0.7874 0.4064)
			(stroke
				(width 0.1524)
				(type default)
			)
			(layer "F.SilkS")
		)
		(fp_line
			(start -0.7874 0.4064)
			(end -0.7874 -0.4064)
			(stroke
				(width 0.1524)
				(type default)
			)
			(layer "F.SilkS")
		)
		(fp_line
			(start -0.12065 -0.305054)
			(end -0.12065 -0.2794)
			(stroke
				(width 0.1)
				(type default)
			)
			(layer "F.Fab")
		)
		(fp_line
			(start -0.67945 -0.305054)
			(end -0.12065 -0.305054)
			(stroke
				(width 0.1)
				(type default)
			)
			(layer "F.Fab")
		)
		(fp_line
			(start 0.67945 -0.3048)
			(end 0.67945 0.3048)
			(stroke
				(width 0.1)
				(type default)
			)
			(layer "F.Fab")
		)
		(fp_line
			(start 0.12065 -0.3048)
			(end 0.67945 -0.3048)
			(stroke
				(width 0.1)
				(type default)
			)
			(layer "F.Fab")
		)
		(fp_line
			(start 0.12065 -0.2794)
			(end 0.12065 -0.3048)
			(stroke
				(width 0.1)
				(type default)
			)
			(layer "F.Fab")
		)
		(fp_line
			(start -0.12065 -0.2794)
			(end 0.12065 -0.2794)
			(stroke
				(width 0.1)
				(type default)
			)
			(layer "F.Fab")
		)
		(fp_line
			(start 0.120396 0.2794)
			(end -0.12065 0.2794)
			(stroke
				(width 0.1)
				(type default)
			)
			(layer "F.Fab")
		)
		(fp_line
			(start -0.12065 0.2794)
			(end -0.12065 0.3048)
			(stroke
				(width 0.1)
				(type default)
			)
			(layer "F.Fab")
		)
		(fp_line
			(start 0.67945 0.3048)
			(end 0.120396 0.3048)
			(stroke
				(width 0.1)
				(type default)
			)
			(layer "F.Fab")
		)
		(fp_line
			(start 0.120396 0.3048)
			(end 0.120396 0.2794)
			(stroke
				(width 0.1)
				(type default)
			)
			(layer "F.Fab")
		)
		(fp_line
			(start -0.12065 0.3048)
			(end -0.67945 0.3048)
			(stroke
				(width 0.1)
				(type default)
			)
			(layer "F.Fab")
		)
		(fp_line
			(start -0.67945 0.3048)
			(end -0.67945 -0.305054)
			(stroke
				(width 0.1)
				(type default)
			)
			(layer "F.Fab")
		)
		(pad "1" smd circle
			(at -0.40005 0 90)
			(size 0 0)
			(layers "F.Cu" "F.Mask" "F.Paste")
			(net "SW_PVDDCR_CPU0_P0_BOOT3_RC")
		)
		(pad "2" smd circle
			(at 0.40005 0 90)
			(size 0 0)
			(layers "F.Cu" "F.Mask" "F.Paste")
			(net "SW_PVDDCR_CPU0_P0_PH3")
		)
	)
	(footprint ""
		(layer "F.Cu")
		(at 454.611994 -46.264576 -90)
		(property "Reference" "PR833"
			(at 0 0 270)
			(layer "F.SilkS")
			(hide yes)
			(effects
				(font
					(size 1.27 1.27)
				)
			)
		)
		(property "Value" ""
			(at 0 0 270)
			(layer "F.Fab")
			(effects
				(font
					(size 1.27 1.27)
				)
			)
		)
		(duplicate_pad_numbers_are_jumpers no)
		(fp_line
			(start -0.7874 0.4064)
			(end -0.7874 -0.4064)
			(stroke
				(width 0.1524)
				(type default)
			)
			(layer "F.SilkS")
		)
		(fp_line
			(start 0.7874 0.4064)
			(end -0.7874 0.4064)
			(stroke
				(width 0.1524)
				(type default)
			)
			(layer "F.SilkS")
		)
		(fp_line
			(start -0.7874 -0.4064)
			(end 0.7874 -0.4064)
			(stroke
				(width 0.1524)
				(type default)
			)
			(layer "F.SilkS")
		)
		(fp_line
			(start 0.7874 -0.4064)
			(end 0.7874 0.4064)
			(stroke
				(width 0.1524)
				(type default)
			)
			(layer "F.SilkS")
		)
		(fp_line
			(start -0.67945 0.3048)
			(end -0.67945 -0.305054)
			(stroke
				(width 0.1)
				(type default)
			)
			(layer "F.Fab")
		)
		(fp_line
			(start -0.12065 0.3048)
			(end -0.67945 0.3048)
			(stroke
				(width 0.1)
				(type default)
			)
			(layer "F.Fab")
		)
		(fp_line
			(start 0.120396 0.3048)
			(end 0.120396 0.2794)
			(stroke
				(width 0.1)
				(type default)
			)
			(layer "F.Fab")
		)
		(fp_line
			(start 0.67945 0.3048)
			(end 0.120396 0.3048)
			(stroke
				(width 0.1)
				(type default)
			)
			(layer "F.Fab")
		)
		(fp_line
			(start -0.12065 0.2794)
			(end -0.12065 0.3048)
			(stroke
				(width 0.1)
				(type default)
			)
			(layer "F.Fab")
		)
		(fp_line
			(start 0.120396 0.2794)
			(end -0.12065 0.2794)
			(stroke
				(width 0.1)
				(type default)
			)
			(layer "F.Fab")
		)
		(fp_line
			(start -0.12065 -0.2794)
			(end 0.12065 -0.2794)
			(stroke
				(width 0.1)
				(type default)
			)
			(layer "F.Fab")
		)
		(fp_line
			(start 0.12065 -0.2794)
			(end 0.12065 -0.3048)
			(stroke
				(width 0.1)
				(type default)
			)
			(layer "F.Fab")
		)
		(fp_line
			(start 0.12065 -0.3048)
			(end 0.67945 -0.3048)
			(stroke
				(width 0.1)
				(type default)
			)
			(layer "F.Fab")
		)
		(fp_line
			(start 0.67945 -0.3048)
			(end 0.67945 0.3048)
			(stroke
				(width 0.1)
				(type default)
			)
			(layer "F.Fab")
		)
		(fp_line
			(start -0.67945 -0.305054)
			(end -0.12065 -0.305054)
			(stroke
				(width 0.1)
				(type default)
			)
			(layer "F.Fab")
		)
		(fp_line
			(start -0.12065 -0.305054)
			(end -0.12065 -0.2794)
			(stroke
				(width 0.1)
				(type default)
			)
			(layer "F.Fab")
		)
		(pad "1" smd circle
			(at -0.40005 0 270)
			(size 0 0)
			(layers "F.Cu" "F.Mask" "F.Paste")
			(net "P3V3_AUX_SS")
		)
		(pad "2" smd circle
			(at 0.40005 0 270)
			(size 0 0)
			(layers "F.Cu" "F.Mask" "F.Paste")
			(net "GND")
		)
	)
	(footprint ""
		(layer "F.Cu")
		(at 459.437486 -93.627448)
		(property "Reference" "U224"
			(at -1.651 -1.793748 0)
			(unlocked yes)
			(layer "F.SilkS")
			(effects
				(font
					(size 0.7874 0.5842)
					(thickness 0.1524)
				)
				(justify left)
			)
		)
		(property "Value" ""
			(at 0 0 0)
			(layer "F.Fab")
			(effects
				(font
					(size 1.27 1.27)
				)
			)
		)
		(duplicate_pad_numbers_are_jumpers no)
		(fp_line
			(start -1.400048 1.100074)
			(end -1.400048 -1.100074)
			(stroke
				(width 0.1524)
				(type default)
			)
			(layer "F.SilkS")
		)
		(fp_line
			(start 1.400048 -1.100074)
			(end -1.400048 -1.100074)
			(stroke
				(width 0.1524)
				(type default)
			)
			(layer "F.SilkS")
		)
		(fp_line
			(start 1.400048 -1.100074)
			(end 1.400048 1.100074)
			(stroke
				(width 0.1524)
				(type default)
			)
			(layer "F.SilkS")
		)
		(fp_line
			(start 1.400048 1.100074)
			(end -1.400048 1.100074)
			(stroke
				(width 0.1524)
				(type default)
			)
			(layer "F.SilkS")
		)
		(fp_poly
			(pts
				(xy -2.606548 -0.141986) (xy -2.606548 -1.157986) (xy -1.590548 -0.649986)
			)
			(stroke
				(width 0)
				(type default)
			)
			(fill yes)
			(layer "F.SilkS")
		)
		(fp_line
			(start -0.674878 -1.100074)
			(end 0.674878 -1.100074)
			(stroke
				(width 0.1)
				(type default)
			)
			(layer "F.Fab")
		)
		(fp_line
			(start -0.674878 1.100074)
			(end -0.674878 -1.100074)
			(stroke
				(width 0.1)
				(type default)
			)
			(layer "F.Fab")
		)
		(fp_line
			(start 0.674878 -1.100074)
			(end 0.674878 1.100074)
			(stroke
				(width 0.1)
				(type default)
			)
			(layer "F.Fab")
		)
		(fp_line
			(start 0.674878 1.100074)
			(end -0.674878 1.100074)
			(stroke
				(width 0.1)
				(type default)
			)
			(layer "F.Fab")
		)
		(fp_poly
			(pts
				(xy -1.590548 -0.649986) (xy -2.606548 -1.157986) (xy -2.606548 -0.141986)
			)
			(stroke
				(width 0)
				(type default)
			)
			(fill yes)
			(layer "F.Fab")
		)
		(pad "1" smd rect
			(at -0.94996 -0.649986 270)
			(size 0.4318 0.6096)
			(layers "F.Cu" "F.Mask" "F.Paste")
			(net "OCP_SFF_AUX_PWR_EN_R2")
		)
		(pad "2" smd rect
			(at -0.94996 0 270)
			(size 0.4318 0.6096)
			(layers "F.Cu" "F.Mask" "F.Paste")
			(net "RST_SMB_SWITCH_N")
		)
		(pad "3" smd rect
			(at -0.94996 0.649986 270)
			(size 0.4318 0.6096)
			(layers "F.Cu" "F.Mask" "F.Paste")
			(net "GND")
		)
		(pad "4" smd rect
			(at 0.94996 0.649986 270)
			(size 0.4318 0.6096)
			(layers "F.Cu" "F.Mask" "F.Paste")
			(net "RST_HP_OCP_SFF_R_N")
		)
		(pad "5" smd rect
			(at 0.94996 -0.649986 270)
			(size 0.4318 0.6096)
			(layers "F.Cu" "F.Mask" "F.Paste")
			(net "P3V3_AUX")
		)
	)
	(footprint ""
		(layer "F.Cu")
		(at 61.709554 -375.49963 -90)
		(property "Reference" "C817"
			(at 0 0 270)
			(layer "F.SilkS")
			(hide yes)
			(effects
				(font
					(size 1.27 1.27)
				)
			)
		)
		(property "Value" ""
			(at 0 0 270)
			(layer "F.Fab")
			(effects
				(font
					(size 1.27 1.27)
				)
			)
		)
		(duplicate_pad_numbers_are_jumpers no)
		(fp_line
			(start -0.299974 0.150114)
			(end -0.299974 -0.150114)
			(stroke
				(width 0.1)
				(type default)
			)
			(layer "F.Fab")
		)
		(fp_line
			(start 0.299974 0.150114)
			(end -0.299974 0.150114)
			(stroke
				(width 0.1)
				(type default)
			)
			(layer "F.Fab")
		)
		(fp_line
			(start -0.299974 -0.150114)
			(end 0.299974 -0.150114)
			(stroke
				(width 0.1)
				(type default)
			)
			(layer "F.Fab")
		)
		(fp_line
			(start 0.299974 -0.150114)
			(end 0.299974 0.150114)
			(stroke
				(width 0.1)
				(type default)
			)
			(layer "F.Fab")
		)
		(pad "1" smd rect
			(at -0.2667 0 270)
			(size 0.3048 0.381)
			(layers "F.Cu" "F.Mask" "F.Paste")
			(net "P5E_CPU1_P0_TX_C_DP<10>")
		)
		(pad "2" smd rect
			(at 0.2667 0 270)
			(size 0.3048 0.381)
			(layers "F.Cu" "F.Mask" "F.Paste")
			(net "P5E_CPU1_P0_TX_DP<10>")
		)
	)
	(footprint ""
		(layer "F.Cu")
		(at 189.103 -133.568948 90)
		(property "Reference" "R856"
			(at 0 0 90)
			(layer "F.SilkS")
			(hide yes)
			(effects
				(font
					(size 1.27 1.27)
				)
			)
		)
		(property "Value" ""
			(at 0 0 90)
			(layer "F.Fab")
			(effects
				(font
					(size 1.27 1.27)
				)
			)
		)
		(duplicate_pad_numbers_are_jumpers no)
		(fp_line
			(start 0.7874 -0.4064)
			(end 0.7874 0.4064)
			(stroke
				(width 0.1524)
				(type default)
			)
			(layer "F.SilkS")
		)
		(fp_line
			(start -0.7874 -0.4064)
			(end 0.7874 -0.4064)
			(stroke
				(width 0.1524)
				(type default)
			)
			(layer "F.SilkS")
		)
		(fp_line
			(start 0.7874 0.4064)
			(end -0.7874 0.4064)
			(stroke
				(width 0.1524)
				(type default)
			)
			(layer "F.SilkS")
		)
		(fp_line
			(start -0.7874 0.4064)
			(end -0.7874 -0.4064)
			(stroke
				(width 0.1524)
				(type default)
			)
			(layer "F.SilkS")
		)
		(fp_line
			(start -0.12065 -0.305054)
			(end -0.12065 -0.2794)
			(stroke
				(width 0.1)
				(type default)
			)
			(layer "F.Fab")
		)
		(fp_line
			(start -0.67945 -0.305054)
			(end -0.12065 -0.305054)
			(stroke
				(width 0.1)
				(type default)
			)
			(layer "F.Fab")
		)
		(fp_line
			(start 0.67945 -0.3048)
			(end 0.67945 0.3048)
			(stroke
				(width 0.1)
				(type default)
			)
			(layer "F.Fab")
		)
		(fp_line
			(start 0.12065 -0.3048)
			(end 0.67945 -0.3048)
			(stroke
				(width 0.1)
				(type default)
			)
			(layer "F.Fab")
		)
		(fp_line
			(start 0.12065 -0.2794)
			(end 0.12065 -0.3048)
			(stroke
				(width 0.1)
				(type default)
			)
			(layer "F.Fab")
		)
		(fp_line
			(start -0.12065 -0.2794)
			(end 0.12065 -0.2794)
			(stroke
				(width 0.1)
				(type default)
			)
			(layer "F.Fab")
		)
		(fp_line
			(start 0.120396 0.2794)
			(end -0.12065 0.2794)
			(stroke
				(width 0.1)
				(type default)
			)
			(layer "F.Fab")
		)
		(fp_line
			(start -0.12065 0.2794)
			(end -0.12065 0.3048)
			(stroke
				(width 0.1)
				(type default)
			)
			(layer "F.Fab")
		)
		(fp_line
			(start 0.67945 0.3048)
			(end 0.120396 0.3048)
			(stroke
				(width 0.1)
				(type default)
			)
			(layer "F.Fab")
		)
		(fp_line
			(start 0.120396 0.3048)
			(end 0.120396 0.2794)
			(stroke
				(width 0.1)
				(type default)
			)
			(layer "F.Fab")
		)
		(fp_line
			(start -0.12065 0.3048)
			(end -0.67945 0.3048)
			(stroke
				(width 0.1)
				(type default)
			)
			(layer "F.Fab")
		)
		(fp_line
			(start -0.67945 0.3048)
			(end -0.67945 -0.305054)
			(stroke
				(width 0.1)
				(type default)
			)
			(layer "F.Fab")
		)
		(pad "1" smd circle
			(at -0.40005 0 90)
			(size 0 0)
			(layers "F.Cu" "F.Mask" "F.Paste")
			(net "FM_HDT_HDR_RESET_N")
		)
		(pad "2" smd circle
			(at 0.40005 0 90)
			(size 0 0)
			(layers "F.Cu" "F.Mask" "F.Paste")
			(net "HDT_HDR_RESET_N")
		)
	)
	(footprint ""
		(layer "F.Cu")
		(at 168.39057 -123.683014)
		(property "Reference" "R6138"
			(at 0 0 0)
			(layer "F.SilkS")
			(hide yes)
			(effects
				(font
					(size 1.27 1.27)
				)
			)
		)
		(property "Value" ""
			(at 0 0 0)
			(layer "F.Fab")
			(effects
				(font
					(size 1.27 1.27)
				)
			)
		)
		(duplicate_pad_numbers_are_jumpers no)
		(fp_line
			(start -0.7874 -0.4064)
			(end 0.7874 -0.4064)
			(stroke
				(width 0.1524)
				(type default)
			)
			(layer "F.SilkS")
		)
		(fp_line
			(start -0.7874 0.4064)
			(end -0.7874 -0.4064)
			(stroke
				(width 0.1524)
				(type default)
			)
			(layer "F.SilkS")
		)
		(fp_line
			(start 0.7874 -0.4064)
			(end 0.7874 0.4064)
			(stroke
				(width 0.1524)
				(type default)
			)
			(layer "F.SilkS")
		)
		(fp_line
			(start 0.7874 0.4064)
			(end -0.7874 0.4064)
			(stroke
				(width 0.1524)
				(type default)
			)
			(layer "F.SilkS")
		)
		(fp_line
			(start -0.67945 -0.305054)
			(end -0.12065 -0.305054)
			(stroke
				(width 0.1)
				(type default)
			)
			(layer "F.Fab")
		)
		(fp_line
			(start -0.67945 0.3048)
			(end -0.67945 -0.305054)
			(stroke
				(width 0.1)
				(type default)
			)
			(layer "F.Fab")
		)
		(fp_line
			(start -0.12065 -0.305054)
			(end -0.12065 -0.2794)
			(stroke
				(width 0.1)
				(type default)
			)
			(layer "F.Fab")
		)
		(fp_line
			(start -0.12065 -0.2794)
			(end 0.12065 -0.2794)
			(stroke
				(width 0.1)
				(type default)
			)
			(layer "F.Fab")
		)
		(fp_line
			(start -0.12065 0.2794)
			(end -0.12065 0.3048)
			(stroke
				(width 0.1)
				(type default)
			)
			(layer "F.Fab")
		)
		(fp_line
			(start -0.12065 0.3048)
			(end -0.67945 0.3048)
			(stroke
				(width 0.1)
				(type default)
			)
			(layer "F.Fab")
		)
		(fp_line
			(start 0.120396 0.2794)
			(end -0.12065 0.2794)
			(stroke
				(width 0.1)
				(type default)
			)
			(layer "F.Fab")
		)
		(fp_line
			(start 0.120396 0.3048)
			(end 0.120396 0.2794)
			(stroke
				(width 0.1)
				(type default)
			)
			(layer "F.Fab")
		)
		(fp_line
			(start 0.12065 -0.3048)
			(end 0.67945 -0.3048)
			(stroke
				(width 0.1)
				(type default)
			)
			(layer "F.Fab")
		)
		(fp_line
			(start 0.12065 -0.2794)
			(end 0.12065 -0.3048)
			(stroke
				(width 0.1)
				(type default)
			)
			(layer "F.Fab")
		)
		(fp_line
			(start 0.67945 -0.3048)
			(end 0.67945 0.3048)
			(stroke
				(width 0.1)
				(type default)
			)
			(layer "F.Fab")
		)
		(fp_line
			(start 0.67945 0.3048)
			(end 0.120396 0.3048)
			(stroke
				(width 0.1)
				(type default)
			)
			(layer "F.Fab")
		)
		(pad "1" smd circle
			(at -0.40005 0)
			(size 0 0)
			(layers "F.Cu" "F.Mask" "F.Paste")
			(net "P3V3_AUX")
		)
		(pad "2" smd circle
			(at 0.40005 0)
			(size 0 0)
			(layers "F.Cu" "F.Mask" "F.Paste")
			(net "FM_BOARD_BMC_SKU_ID2")
		)
	)
	(footprint ""
		(layer "F.Cu")
		(at 9.74471 -71.860664)
		(property "Reference" "R3134"
			(at 0 0 0)
			(layer "F.SilkS")
			(hide yes)
			(effects
				(font
					(size 1.27 1.27)
				)
			)
		)
		(property "Value" ""
			(at 0 0 0)
			(layer "F.Fab")
			(effects
				(font
					(size 1.27 1.27)
				)
			)
		)
		(duplicate_pad_numbers_are_jumpers no)
		(fp_line
			(start -0.7874 -0.4064)
			(end 0.7874 -0.4064)
			(stroke
				(width 0.1524)
				(type default)
			)
			(layer "F.SilkS")
		)
		(fp_line
			(start -0.7874 0.4064)
			(end -0.7874 -0.4064)
			(stroke
				(width 0.1524)
				(type default)
			)
			(layer "F.SilkS")
		)
		(fp_line
			(start 0.7874 -0.4064)
			(end 0.7874 0.4064)
			(stroke
				(width 0.1524)
				(type default)
			)
			(layer "F.SilkS")
		)
		(fp_line
			(start 0.7874 0.4064)
			(end -0.7874 0.4064)
			(stroke
				(width 0.1524)
				(type default)
			)
			(layer "F.SilkS")
		)
		(fp_line
			(start -0.67945 -0.305054)
			(end -0.12065 -0.305054)
			(stroke
				(width 0.1)
				(type default)
			)
			(layer "F.Fab")
		)
		(fp_line
			(start -0.67945 0.3048)
			(end -0.67945 -0.305054)
			(stroke
				(width 0.1)
				(type default)
			)
			(layer "F.Fab")
		)
		(fp_line
			(start -0.12065 -0.305054)
			(end -0.12065 -0.2794)
			(stroke
				(width 0.1)
				(type default)
			)
			(layer "F.Fab")
		)
		(fp_line
			(start -0.12065 -0.2794)
			(end 0.12065 -0.2794)
			(stroke
				(width 0.1)
				(type default)
			)
			(layer "F.Fab")
		)
		(fp_line
			(start -0.12065 0.2794)
			(end -0.12065 0.3048)
			(stroke
				(width 0.1)
				(type default)
			)
			(layer "F.Fab")
		)
		(fp_line
			(start -0.12065 0.3048)
			(end -0.67945 0.3048)
			(stroke
				(width 0.1)
				(type default)
			)
			(layer "F.Fab")
		)
		(fp_line
			(start 0.120396 0.2794)
			(end -0.12065 0.2794)
			(stroke
				(width 0.1)
				(type default)
			)
			(layer "F.Fab")
		)
		(fp_line
			(start 0.120396 0.3048)
			(end 0.120396 0.2794)
			(stroke
				(width 0.1)
				(type default)
			)
			(layer "F.Fab")
		)
		(fp_line
			(start 0.12065 -0.3048)
			(end 0.67945 -0.3048)
			(stroke
				(width 0.1)
				(type default)
			)
			(layer "F.Fab")
		)
		(fp_line
			(start 0.12065 -0.2794)
			(end 0.12065 -0.3048)
			(stroke
				(width 0.1)
				(type default)
			)
			(layer "F.Fab")
		)
		(fp_line
			(start 0.67945 -0.3048)
			(end 0.67945 0.3048)
			(stroke
				(width 0.1)
				(type default)
			)
			(layer "F.Fab")
		)
		(fp_line
			(start 0.67945 0.3048)
			(end 0.120396 0.3048)
			(stroke
				(width 0.1)
				(type default)
			)
			(layer "F.Fab")
		)
		(pad "1" smd circle
			(at -0.40005 0)
			(size 0 0)
			(layers "F.Cu" "F.Mask" "F.Paste")
			(net "P3V3_AUX")
		)
		(pad "2" smd circle
			(at 0.40005 0)
			(size 0 0)
			(layers "F.Cu" "F.Mask" "F.Paste")
			(net "OCP_V3_2_PRSNT2_R_N")
		)
	)
)
